FILE_TYPE = CONNECTIVITY;
{Allegro Design Entry HDL 17.2-2016 S081 (4005846) 1/11/2022}
"PAGE_NUMBER" = 46;
0"NC";
1"P3V3_AUX\g";
2"P3V3_AUX\g";
3"P3V3_AUX\g";
4"P3V3_AUX\g";
5"P3V3_AUX\g";
6"P3V3_AUX\g";
7"P3V3_AUX\g";
8"P3V3_AUX\g";
9"P3V3_AUX\g";
10"GND\g";
11"GND\g";
12"GND\g";
13"GND\g";
14"SPI_BMC_TPM_CLK";
15"SPI_BMC_TPM_MISO";
16"SPI_BMC_TPM_MOSI_R";
17"SPI_BMC_TPM_CS2_N_R";
18"SMB_BMC_TPM_MM16_SDA";
19"SPI_BMC_TPM_CS2_R_N";
20"SPI_BMC_TPM_CLK_R";
21"SPI_TPM_CS_R_N";
22"SPI_TPM_CS_N_R";
23"RST_BMC_EXTRST_R3_N";
24"SPI_BMC_TPM_MOSI";
25"RST_BMC_EXTRST_R2_N";
26"SMB_BMC_MM16_R5_SDA";
27"SPI_BMC_TPM_MISO_R";
28"FM_TPM_PRSNT_0_N";
29"SMB_BMC_TPM_MM16_SCL";
30"IRQ_BMC_TPM_SPI_R_N";
31"FM_TPM_PRSNT_1_N";
32"IRQ_TPM_SPI_N";
33"SMB_BMC_MM16_R5_SCL";
34"IRQ_PCH_TPM_SPI_N";
35"IRQ_PCH_TPM_SPI_R_N";
36"SMB_PCH_TPM_SCL";
37"SPI_SYS_R1_CLK";
38"RST_PLTRST_TPM_N";
39"SPI_SYS_R_MOSI";
40"RST_PLTRST_N";
41"SPI_SYS_R1_MOSI";
42"SPI_SYS_R1_MISO";
43"SPI_SYS_R_CLK";
44"SPI_SYS_R_MISO";
45"SMB_PCH_TPM_SDA";
%"Q_CAP"
"1","(-6875,-4425)","0","pure_quanta","I102";
;
TOLERANCE"10%"
MATERIAL"X7R"
VOLTAGE"25V"
VALUE"0.1UF"
PART_NUMBER"CH4104K1B00"
PACK_TYPE"0402"
CDS_LIB"pure_quanta"
LOCATION"C144"
$SEC"1"
CDS_SEC"1";
"B"
$PN"2"10;
"A"
$PN"1"9;
%"Q_RES"
"2","(-6300,-5325)","2","pure_quanta","I104";
;
VALUE"10K"
TOLERANCE"1%"
PACK_TYPE"0402LF"
PART_NUMBER"CS31002FB08"
MATERIAL"CHIP"
WATTAGE"1/16W"
CDS_LIB"pure_quanta"
LOCATION"R50"
$SEC"1"
CDS_SEC"1";
"A"
$PN"1"3;
"B"
$PN"2"31;
%"Q_RES"
"1","(-6600,-5650)","2","pure_quanta","I105";
;
MATERIAL"CHIP"
VALUE"0"
PART_NUMBER"CS00002JB13"
PACK_TYPE"0402LF"
WATTAGE"1/16W"
TOLERANCE"5%"
SEC_TYPE"0402LF"
CDS_LIB"pure_quanta"
LOCATION"R113"
SEC"1";
"B"
$PN"2"30;
"A"
$PN"1"32;
%"Q_RES"
"1","(-6600,-5700)","6","pure_quanta","I106";
;
VALUE"33.2"
MATERIAL"CHIP"
TOLERANCE"1%"
PART_NUMBER"CS03322FB03"
WATTAGE"1/16W"
PACK_TYPE"0402LF"
CDS_LIB"pure_quanta"
LOCATION"R47"
$SEC"1"
CDS_SEC"1";
"B"
$PN"2"33;
"A"
$PN"1"29;
%"UNIVERSAL_POWER"
"1","(-7250,-4125)","0","logical_power","I107";
;
HDL_POWER"P3V3_AUX"
CDS_LIB"logical_power";
"A"9;
%"Q_CAP"
"1","(-7250,-4425)","0","pure_quanta","I108";
;
PACK_TYPE"C0402"
VALUE"10UF"
TOLERANCE"20%"
MATERIAL"X6S"
PART_NUMBER"CH6101MEB01"
VOLTAGE"6.3V"
CDS_LIB"pure_quanta"
LOCATION"C143"
$SEC"1"
CDS_SEC"1";
"B"
$PN"2"10;
"A"
$PN"1"9;
%"UNIVERSAL_GND"
"1","(-7250,-4875)","0","logical_power","I109";
;
HDL_POWER"GND"
CDS_LIB"logical_power";
"A"10;
%"UNIVERSAL_GND"
"1","(-7525,-6100)","0","logical_power","I112";
;
HDL_POWER"GND"
CDS_LIB"logical_power";
"A"11;
%"SCONN11_9192031111LF"
"1","(-7950,-5725)","0","pure_quanta","I113";
;
MATERIAL"IO"
PART_NUMBER"DFHS11FS009"
PART_TYPE"SMLF"
VALUE"SCONN11_91920-31111LF"
CDS_LMAN_SYM_OUTLINE"-150,275,150,-275"
NEEDS_NO_SIZE"TRUE"
CDS_LIB"pure_quanta"
LOCATION"J10"
$SEC"1"
CDS_SEC"1";
"11"
$PN"11"11;
"10"
$PN"10"29;
"9"
$PN"9"30;
"8"
$PN"8"31;
"7"
$PN"7"9;
"6"
$PN"6"18;
"G2"
$PN"G2"11;
"G1"
$PN"G1"11;
"2"
$PN"2"23;
"5"
$PN"5"17;
"4"
$PN"4"27;
"3"
$PN"3"16;
"1"
$PN"1"20;
%"Q_RES"
"1","(-9900,-5550)","2","pure_quanta","I114";
;
PACK_TYPE"0402LF"
MATERIAL"CHIP"
WATTAGE"1/16W"
VALUE"0"
TOLERANCE"5%"
PART_NUMBER"CS00002JB13"
CDS_LIB"pure_quanta"
LOCATION"R109"
$SEC"1"
CDS_SEC"1";
"B"
$PN"2"14;
"A"
$PN"1"20;
%"Q_RES"
"1","(-9900,-5650)","2","pure_quanta","I115";
;
PACK_TYPE"0402LF"
MATERIAL"CHIP"
WATTAGE"1/16W"
VALUE"0"
TOLERANCE"5%"
PART_NUMBER"CS00002JB13"
CDS_LIB"pure_quanta"
LOCATION"R97"
$SEC"1"
CDS_SEC"1";
"B"
$PN"2"24;
"A"
$PN"1"16;
%"Q_RES"
"1","(-9900,-5600)","2","pure_quanta","I116";
;
WATTAGE"1/16W"
PACK_TYPE"0402LF"
MATERIAL"CHIP"
VALUE"0"
TOLERANCE"5%"
PART_NUMBER"CS00002JB13"
CDS_LIB"pure_quanta"
LOCATION"R110"
$SEC"1"
CDS_SEC"1";
"B"
$PN"2"25;
"A"
$PN"1"23;
%"Q_RES"
"1","(-9900,-5800)","0","pure_quanta","I117";
;
VALUE"33.2"
MATERIAL"CHIP"
TOLERANCE"1%"
PART_NUMBER"CS03322FB03"
PACK_TYPE"0402LF"
WATTAGE"1/16W"
CDS_LIB"pure_quanta"
LOCATION"R33"
$SEC"1"
CDS_SEC"1";
"B"
$PN"2"18;
"A"
$PN"1"26;
%"Q_RES"
"1","(-9900,-5700)","2","pure_quanta","I119";
;
PACK_TYPE"0402LF"
MATERIAL"CHIP"
WATTAGE"1/16W"
TOLERANCE"5%"
VALUE"0"
PART_NUMBER"CS00002JB13"
CDS_LIB"pure_quanta"
LOCATION"R98"
$SEC"1"
CDS_SEC"1";
"B"
$PN"2"15;
"A"
$PN"1"27;
%"Q_RES"
"2","(-6550,-2450)","2","pure_quanta","I132";
;
PART_NUMBER"CS31002FB08"
MATERIAL"CHIP"
WATTAGE"1/16W"
PACK_TYPE"0402LF"
TOLERANCE"1%"
VALUE"10K"
CDS_LIB"pure_quanta"
LOCATION"R136"
$SEC"1"
CDS_SEC"1";
"A"
$PN"1"4;
"B"
$PN"2"36;
%"UNIVERSAL_POWER"
"1","(-6550,-2075)","0","logical_power","I133";
;
HDL_POWER"P3V3_AUX"
CDS_LIB"logical_power";
"A"4;
%"Q_RES"
"2","(-9000,-3250)","2","pure_quanta","I134";
;
WATTAGE"1/16W"
PACK_TYPE"0402LF"
VALUE"10K"
MATERIAL"CHIP"
TOLERANCE"1%"
PART_NUMBER"CS31002FB08"
CDS_LIB"pure_quanta"
LOCATION"R126"
$SEC"1"
CDS_SEC"1";
"A"
$PN"1"45;
"B"
$PN"2"8;
%"UNIVERSAL_POWER"
"1","(-8750,-3150)","0","logical_power","I135";
;
HDL_POWER"P3V3_AUX"
CDS_LIB"logical_power";
"A"8;
%"Q_RES"
"1","(-9825,-2825)","0","pure_quanta","I136";
;
PART_NUMBER"CS02202FB02"
MATERIAL"CHIP"
VALUE"22"
CDS_LIB"pure_quanta"
PACK_TYPE"0402LF"
WATTAGE"1/16W"
TOLERANCE"1%"
LOCATION"R499"
$SEC"1"
CDS_SEC"1";
"B"
$PN"2"42;
"A"
$PN"1"44;
%"Q_RES"
"1","(-9825,-2775)","0","pure_quanta","I137";
;
VALUE"22"
MATERIAL"CHIP"
PART_NUMBER"CS02202FB02"
CDS_LIB"pure_quanta"
PACK_TYPE"0402LF"
WATTAGE"1/16W"
TOLERANCE"1%"
LOCATION"R498"
$SEC"1"
CDS_SEC"1";
"B"
$PN"2"41;
"A"
$PN"1"39;
%"UNIVERSAL_POWER"
"1","(-10225,-4675)","0","logical_power","I138";
;
HDL_POWER"P3V3_AUX"
CDS_LIB"logical_power";
"A"1;
%"Q_RES"
"2","(-10225,-5100)","0","pure_quanta","I139";
;
VALUE"4.7K"
MATERIAL"EMPTY"
PART_NUMBER"CS24702FB10"
CDS_LIB"pure_quanta"
TOLERANCE"1%"
WATTAGE"1/16W"
PACK_TYPE"0402LF"
$LOCATION"R408"
CDS_LOCATION"R408"
$SEC"1"
CDS_SEC"1";
"A"
$PN"1"1;
"B"
$PN"2"14;
%"Q_RES"
"2","(-10125,-5100)","0","pure_quanta","I140";
;
VALUE"4.7K"
MATERIAL"EMPTY"
WATTAGE"1/16W"
TOLERANCE"1%"
PACK_TYPE"0402LF"
CDS_LIB"pure_quanta"
PART_NUMBER"CS24702FB10"
$LOCATION"R414"
CDS_LOCATION"R414"
$SEC"1"
CDS_SEC"1";
"A"
$PN"1"1;
"B"
$PN"2"15;
%"UNIVERSAL_POWER"
"1","(-6300,-5050)","0","logical_power","I145";
;
HDL_POWER"P3V3_AUX"
CDS_LIB"logical_power";
"A"3;
%"UNIVERSAL_POWER"
"1","(-5250,-2000)","0","logical_power","I146";
;
HDL_POWER"P3V3_AUX"
CDS_LIB"logical_power";
"A"5;
%"Q_RES"
"1","(-9900,-5750)","2","pure_quanta","I147";
;
MATERIAL"CHIP"
VALUE"33.2"
WATTAGE"1/16W"
TOLERANCE"1%"
PACK_TYPE"0402LF"
PART_NUMBER"CS03322FB03"
CDS_LIB"pure_quanta"
LOCATION"R100"
$SEC"1"
CDS_SEC"1";
"B"
$PN"2"19;
"A"
$PN"1"17;
%"SCONN11_9192031111LF"
"1","(-7875,-2850)","0","pure_quanta","I56";
;
VALUE"SCONN11_91920-31111LF"
PART_TYPE"SMLF"
MATERIAL"IO"
PART_NUMBER"DFHS11FS009"
CDS_LIB"pure_quanta"
NEEDS_NO_SIZE"TRUE"
CDS_LMAN_SYM_OUTLINE"-150,275,150,-275"
LOCATION"J5"
$SEC"1"
CDS_SEC"1";
"11"
$PN"11"13;
"10"
$PN"10"36;
"9"
$PN"9"35;
"8"
$PN"8"28;
"7"
$PN"7"7;
"6"
$PN"6"45;
"G2"
$PN"G2"13;
"G1"
$PN"G1"13;
"2"
$PN"2"38;
"5"
$PN"5"22;
"4"
$PN"4"42;
"3"
$PN"3"41;
"1"
$PN"1"37;
%"Q_RES"
"1","(-9825,-2675)","2","pure_quanta","I58";
;
MATERIAL"CHIP"
VALUE"33.2"
CDS_LIB"pure_quanta"
SEC_TYPE"0402LF"
WATTAGE"1/16W"
TOLERANCE"1%"
PACK_TYPE"0402LF"
PART_NUMBER"CS03322FB03"
LOCATION"R501"
SEC"1";
"B"
$PN"2"43;
"A"
$PN"1"37;
%"Q_RES"
"1","(-9825,-2725)","2","pure_quanta","I60";
;
MATERIAL"CHIP"
VALUE"0"
PART_NUMBER"CS00002JB13"
CDS_LIB"pure_quanta"
SEC_TYPE"0402LF"
TOLERANCE"5%"
WATTAGE"1/16W"
PACK_TYPE"0402LF"
LOCATION"R503"
SEC"1";
"B"
$PN"2"40;
"A"
$PN"1"38;
%"Q_RES"
"1","(-9825,-2875)","2","pure_quanta","I65";
;
PACK_TYPE"0402LF"
WATTAGE"1/16W"
MATERIAL"CHIP"
VALUE"0"
TOLERANCE"5%"
PART_NUMBER"CS00002JB13"
CDS_LIB"pure_quanta"
SEC_TYPE"0402LF"
LOCATION"R500"
SEC"1";
"B"
$PN"2"21;
"A"
$PN"1"22;
%"Q_CAP"
"1","(-6800,-1550)","0","pure_quanta","I67";
;
PACK_TYPE"0402"
MATERIAL"X7R"
VOLTAGE"25V"
VALUE"0.1UF"
PART_NUMBER"CH4104K1B00"
TOLERANCE"10%"
CDS_LIB"pure_quanta"
LOCATION"C249"
$SEC"1"
CDS_SEC"1";
"B"
$PN"2"12;
"A"
$PN"1"7;
%"UNIVERSAL_POWER"
"1","(-7175,-1250)","0","logical_power","I68";
;
HDL_POWER"P3V3_AUX"
CDS_LIB"logical_power";
"A"7;
%"Q_CAP"
"1","(-7175,-1550)","0","pure_quanta","I69";
;
VALUE"10UF"
PACK_TYPE"C0402"
PART_NUMBER"CH6101MEB01"
TOLERANCE"20%"
MATERIAL"X6S"
VOLTAGE"6.3V"
CDS_LIB"pure_quanta"
LOCATION"C248"
$SEC"1"
CDS_SEC"1";
"B"
$PN"2"12;
"A"
$PN"1"7;
%"UNIVERSAL_GND"
"1","(-7175,-2000)","0","logical_power","I70";
;
HDL_POWER"GND"
CDS_LIB"logical_power";
"A"12;
%"UNIVERSAL_GND"
"1","(-7450,-3225)","0","logical_power","I71";
;
HDL_POWER"GND"
CDS_LIB"logical_power";
"A"13;
%"Q_RES"
"1","(-6275,-2775)","2","pure_quanta","I74";
;
MATERIAL"CHIP"
VALUE"0"
PART_NUMBER"CS00002JB13"
PACK_TYPE"0402LF"
WATTAGE"1/16W"
TOLERANCE"5%"
CDS_LIB"pure_quanta"
LOCATION"R505"
$SEC"1"
CDS_SEC"1";
"B"
$PN"2"35;
"A"
$PN"1"34;
%"Q_RES"
"2","(-5250,-2450)","2","pure_quanta","I75";
;
MATERIAL"CHIP"
PART_NUMBER"CS31002FB08"
PACK_TYPE"0402LF"
VALUE"10K"
TOLERANCE"1%"
WATTAGE"1/16W"
CDS_LIB"pure_quanta"
LOCATION"R464"
$SEC"1"
CDS_SEC"1";
"A"
$PN"1"5;
"B"
$PN"2"28;
%"UNIVERSAL_POWER"
"1","(-4875,-2000)","0","logical_power","I77";
;
HDL_POWER"P3V3_AUX"
CDS_LIB"logical_power";
"A"6;
%"Q_RES"
"2","(-4875,-2475)","2","pure_quanta","I78";
;
WATTAGE"1/16W"
TOLERANCE"1%"
VALUE"10K"
PACK_TYPE"0402LF"
MATERIAL"CHIP"
PART_NUMBER"CS31002FB08"
CDS_LIB"pure_quanta"
LOCATION"R497"
$SEC"1"
CDS_SEC"1";
"A"
$PN"1"6;
"B"
$PN"2"34;
%"UNIVERSAL_POWER"
"1","(-5625,-5050)","0","logical_power","I97";
;
HDL_POWER"P3V3_AUX"
CDS_LIB"logical_power";
"A"2;
%"Q_RES"
"2","(-5625,-5400)","2","pure_quanta","I98";
;
VALUE"10K"
TOLERANCE"1%"
WATTAGE"1/16W"
MATERIAL"CHIP"
PART_NUMBER"CS31002FB08"
PACK_TYPE"0402LF"
CDS_LIB"pure_quanta"
LOCATION"R59"
$SEC"1"
CDS_SEC"1";
"A"
$PN"1"2;
"B"
$PN"2"32;
END.
